# SCM (Grand Teton) — schematic netlist excerpt (pin names and nets, part order shuffled) for the footprints in the layout excerpt that follows; sources: Cadence DE-HDL packaged netlist, KiCad conversion of 12092022_DA0F0TMDCD0_F0T_Management_Board_D_brd_V3_OCP.brd

R31  Q_RES  4.7K 1% CHIP  pkg 0402LF  page 23 : A = P3V3_RGM ; B = V_BMC_DDC_SDA
C213  Q_CAP  100PF 50V 5% EMPTY  pkg 0402  page 23 : A = V_BMC_LS_DDC_SDA_R ; B = GND

(kicad_pcb
	(version 20260206)
	(generator "pcbnew")
	(generator_version "10.0")
	(general
		(thickness 1.6)
		(legacy_teardrops no)
	)
	(paper "A4")
	(title_block
		(title "12092022_DA0F0TMDCD0_F0T_Management_Board_D_brd_V3_OCP.brd")
		(comment 1 "Grand Teton / footprints 83-84 of 1440")
	)
	(layers
		(0 "F.Cu" signal "TOP")
		(4 "In1.Cu" signal "GND")
		(6 "In2.Cu" signal "IN1")
		(8 "In3.Cu" signal "GND1")
		(10 "In4.Cu" signal "IN2")
		(12 "In5.Cu" signal "VCC")
		(14 "In6.Cu" signal "VCC1")
		(16 "In7.Cu" signal "IN3")
		(18 "In8.Cu" signal "GND2")
		(20 "In9.Cu" signal "IN4")
		(22 "In10.Cu" signal "GND3")
		(2 "B.Cu" signal "BOTTOM")
		(9 "F.Adhes" user "F.Adhesive")
		(11 "B.Adhes" user "B.Adhesive")
		(13 "F.Paste" user "Package Geometry/Pastemask Top")
		(15 "B.Paste" user "Package Geometry/Pastemask Bottom")
		(5 "F.SilkS" user "Ref Des/Silkscreen Top")
		(7 "B.SilkS" user "Ref Des/Silkscreen Bottom")
		(1 "F.Mask" user "Board Geometry/Soldermask Top")
		(3 "B.Mask" user "Board Geometry/Soldermask Bottom")
		(17 "Dwgs.User" user "User.Drawings")
		(19 "Cmts.User" user "User.Comments")
		(21 "Eco1.User" user "User.Eco1")
		(23 "Eco2.User" user "User.Eco2")
		(25 "Edge.Cuts" user "Board Geometry/Outline")
		(27 "Margin" user)
		(31 "F.CrtYd" user "Package Geometry/Place Bound Top")
		(29 "B.CrtYd" user "Package Geometry/Place Bound Bottom")
		(35 "F.Fab" user "Ref Des/Assembly Top")
		(33 "B.Fab" user "Ref Des/Assembly Bottom")
	)
	(footprint ""
		(layer "F.Cu")
		(at 32.0548 -20.574 -90)
		(property "Reference" "R31"
			(at 0 0 270)
			(layer "F.SilkS")
			(hide yes)
			(effects
				(font
					(size 1.27 1.27)
				)
			)
		)
		(property "Value" ""
			(at 0 0 270)
			(layer "F.Fab")
			(effects
				(font
					(size 1.27 1.27)
				)
			)
		)
		(duplicate_pad_numbers_are_jumpers no)
		(fp_line
			(start -0.7874 0.4064)
			(end -0.7874 -0.4064)
			(stroke
				(width 0.1524)
				(type default)
			)
			(layer "F.SilkS")
		)
		(fp_line
			(start 0.7874 0.4064)
			(end -0.7874 0.4064)
			(stroke
				(width 0.1524)
				(type default)
			)
			(layer "F.SilkS")
		)
		(fp_line
			(start -0.7874 -0.4064)
			(end 0.7874 -0.4064)
			(stroke
				(width 0.1524)
				(type default)
			)
			(layer "F.SilkS")
		)
		(fp_line
			(start 0.7874 -0.4064)
			(end 0.7874 0.4064)
			(stroke
				(width 0.1524)
				(type default)
			)
			(layer "F.SilkS")
		)
		(fp_line
			(start -0.67945 0.3048)
			(end -0.67945 -0.305054)
			(stroke
				(width 0.1)
				(type default)
			)
			(layer "F.Fab")
		)
		(fp_line
			(start -0.12065 0.3048)
			(end -0.67945 0.3048)
			(stroke
				(width 0.1)
				(type default)
			)
			(layer "F.Fab")
		)
		(fp_line
			(start 0.120396 0.3048)
			(end 0.120396 0.2794)
			(stroke
				(width 0.1)
				(type default)
			)
			(layer "F.Fab")
		)
		(fp_line
			(start 0.67945 0.3048)
			(end 0.120396 0.3048)
			(stroke
				(width 0.1)
				(type default)
			)
			(layer "F.Fab")
		)
		(fp_line
			(start -0.12065 0.2794)
			(end -0.12065 0.3048)
			(stroke
				(width 0.1)
				(type default)
			)
			(layer "F.Fab")
		)
		(fp_line
			(start 0.120396 0.2794)
			(end -0.12065 0.2794)
			(stroke
				(width 0.1)
				(type default)
			)
			(layer "F.Fab")
		)
		(fp_line
			(start -0.12065 -0.2794)
			(end 0.12065 -0.2794)
			(stroke
				(width 0.1)
				(type default)
			)
			(layer "F.Fab")
		)
		(fp_line
			(start 0.12065 -0.2794)
			(end 0.12065 -0.3048)
			(stroke
				(width 0.1)
				(type default)
			)
			(layer "F.Fab")
		)
		(fp_line
			(start 0.12065 -0.3048)
			(end 0.67945 -0.3048)
			(stroke
				(width 0.1)
				(type default)
			)
			(layer "F.Fab")
		)
		(fp_line
			(start 0.67945 -0.3048)
			(end 0.67945 0.3048)
			(stroke
				(width 0.1)
				(type default)
			)
			(layer "F.Fab")
		)
		(fp_line
			(start -0.67945 -0.305054)
			(end -0.12065 -0.305054)
			(stroke
				(width 0.1)
				(type default)
			)
			(layer "F.Fab")
		)
		(fp_line
			(start -0.12065 -0.305054)
			(end -0.12065 -0.2794)
			(stroke
				(width 0.1)
				(type default)
			)
			(layer "F.Fab")
		)
		(pad "1" smd circle
			(at -0.40005 0 270)
			(size 0 0)
			(layers "F.Cu" "F.Mask" "F.Paste")
			(net "P3V3_RGM")
		)
		(pad "2" smd circle
			(at 0.40005 0 270)
			(size 0 0)
			(layers "F.Cu" "F.Mask" "F.Paste")
			(net "V_BMC_DDC_SDA")
		)
	)
	(footprint ""
		(layer "F.Cu")
		(at 27.813 -27.305 180)
		(property "Reference" "C213"
			(at 0 0 180)
			(layer "F.SilkS")
			(hide yes)
			(effects
				(font
					(size 1.27 1.27)
				)
			)
		)
		(property "Value" ""
			(at 0 0 180)
			(layer "F.Fab")
			(effects
				(font
					(size 1.27 1.27)
				)
			)
		)
		(duplicate_pad_numbers_are_jumpers no)
		(fp_line
			(start 0.7874 0.4064)
			(end -0.7874 0.4064)
			(stroke
				(width 0.1524)
				(type default)
			)
			(layer "F.SilkS")
		)
		(fp_line
			(start 0.7874 -0.4064)
			(end 0.7874 0.4064)
			(stroke
				(width 0.1524)
				(type default)
			)
			(layer "F.SilkS")
		)
		(fp_line
			(start -0.7874 0.4064)
			(end -0.7874 -0.4064)
			(stroke
				(width 0.1524)
				(type default)
			)
			(layer "F.SilkS")
		)
		(fp_line
			(start -0.7874 -0.4064)
			(end 0.7874 -0.4064)
			(stroke
				(width 0.1524)
				(type default)
			)
			(layer "F.SilkS")
		)
		(fp_line
			(start 0.67945 0.3048)
			(end 0.120396 0.3048)
			(stroke
				(width 0.1)
				(type default)
			)
			(layer "F.Fab")
		)
		(fp_line
			(start 0.67945 -0.3048)
			(end 0.67945 0.3048)
			(stroke
				(width 0.1)
				(type default)
			)
			(layer "F.Fab")
		)
		(fp_line
			(start 0.12065 -0.2794)
			(end 0.12065 -0.3048)
			(stroke
				(width 0.1)
				(type default)
			)
			(layer "F.Fab")
		)
		(fp_line
			(start 0.12065 -0.3048)
			(end 0.67945 -0.3048)
			(stroke
				(width 0.1)
				(type default)
			)
			(layer "F.Fab")
		)
		(fp_line
			(start 0.120396 0.3048)
			(end 0.120396 0.2794)
			(stroke
				(width 0.1)
				(type default)
			)
			(layer "F.Fab")
		)
		(fp_line
			(start 0.120396 0.2794)
			(end -0.12065 0.2794)
			(stroke
				(width 0.1)
				(type default)
			)
			(layer "F.Fab")
		)
		(fp_line
			(start -0.12065 0.3048)
			(end -0.67945 0.3048)
			(stroke
				(width 0.1)
				(type default)
			)
			(layer "F.Fab")
		)
		(fp_line
			(start -0.12065 0.2794)
			(end -0.12065 0.3048)
			(stroke
				(width 0.1)
				(type default)
			)
			(layer "F.Fab")
		)
		(fp_line
			(start -0.12065 -0.2794)
			(end 0.12065 -0.2794)
			(stroke
				(width 0.1)
				(type default)
			)
			(layer "F.Fab")
		)
		(fp_line
			(start -0.12065 -0.305054)
			(end -0.12065 -0.2794)
			(stroke
				(width 0.1)
				(type default)
			)
			(layer "F.Fab")
		)
		(fp_line
			(start -0.67945 0.3048)
			(end -0.67945 -0.305054)
			(stroke
				(width 0.1)
				(type default)
			)
			(layer "F.Fab")
		)
		(fp_line
			(start -0.67945 -0.305054)
			(end -0.12065 -0.305054)
			(stroke
				(width 0.1)
				(type default)
			)
			(layer "F.Fab")
		)
		(pad "1" smd circle
			(at -0.40005 0 180)
			(size 0 0)
			(layers "F.Cu" "F.Mask" "F.Paste")
			(net "V_BMC_LS_DDC_SDA_R")
		)
		(pad "2" smd circle
			(at 0.40005 0 180)
			(size 0 0)
			(layers "F.Cu" "F.Mask" "F.Paste")
			(net "GND")
		)
	)
)
